(kicad_pcb
	(version 20260206)
	(generator "pcbnew")
	(generator_version "10.0")
	(general
		(thickness 1.6)
		(legacy_teardrops no)
	)
	(paper "A4")
	(title_block
		(title "v1-pdb — T6M_PDB_D_0927_0900.brd")
		(comment 1 "Open CloudServer (Microsoft) / footprints 1-8 of 321")
	)
	(layers
		(0 "F.Cu" signal "TOP")
		(4 "In1.Cu" signal "GND")
		(6 "In2.Cu" signal "IN1")
		(8 "In3.Cu" signal "VCC")
		(10 "In4.Cu" signal "VCC1")
		(12 "In5.Cu" signal "IN2")
		(14 "In6.Cu" signal "GND1")
		(2 "B.Cu" signal "BOTTOM")
		(9 "F.Adhes" user "F.Adhesive")
		(11 "B.Adhes" user "B.Adhesive")
		(13 "F.Paste" user "Package Geometry/Pastemask Top")
		(15 "B.Paste" user "Package Geometry/Pastemask Bottom")
		(5 "F.SilkS" user "Ref Des/Silkscreen Top")
		(7 "B.SilkS" user "Ref Des/Silkscreen Bottom")
		(1 "F.Mask" user "Board Geometry/Soldermask Top")
		(3 "B.Mask" user "Board Geometry/Soldermask Bottom")
		(17 "Dwgs.User" user "User.Drawings")
		(19 "Cmts.User" user "User.Comments")
		(21 "Eco1.User" user "User.Eco1")
		(23 "Eco2.User" user "User.Eco2")
		(25 "Edge.Cuts" user "Board Geometry/Outline")
		(27 "Margin" user)
		(31 "F.CrtYd" user "Package Geometry/Place Bound Top")
		(29 "B.CrtYd" user "Package Geometry/Place Bound Bottom")
		(35 "F.Fab" user "Ref Des/Assembly Top")
		(33 "B.Fab" user "Ref Des/Assembly Bottom")
	)
	(footprint ""
		(layer "F.Cu")
		(at 16.599916 -384.79984)
		(property "Reference" "H6"
			(at -6.4516 -7.127748 0)
			(unlocked yes)
			(layer "F.SilkS")
			(effects
				(font
					(size 0.7874 0.5842)
					(thickness 0.1524)
				)
				(justify left)
			)
		)
		(property "Value" ""
			(at 0 0 0)
			(layer "F.Fab")
			(effects
				(font
					(size 1.27 1.27)
				)
			)
		)
		(duplicate_pad_numbers_are_jumpers no)
		(fp_circle
			(center 0 0)
			(end 7.999984 0)
			(stroke
				(width 0.1524)
				(type default)
			)
			(fill no)
			(layer "F.SilkS")
		)
		(fp_circle
			(center 0 0)
			(end 14.7066 0)
			(stroke
				(width 0.1524)
				(type default)
			)
			(fill no)
			(layer "B.SilkS")
		)
		(fp_poly
			(pts
				(arc
					(start 0 5.0038)
					(mid 0 -5.0038)
					(end 0 5.0038)
				)
			)
			(stroke
				(width 0)
				(type default)
			)
			(fill no)
			(layer "F.CrtYd")
		)
		(pad "" np_thru_hole circle
			(at 0 0)
			(size 4.0132 4.0132)
			(drill 4.0132)
			(layers "*.Cu" "*.Mask")
			(clearance 0.381)
			(thermal_gap 0.381)
		)
		(pad "2" thru_hole circle
			(at 0 -3.50012)
			(size 0.762 0.762)
			(drill 0.5588)
			(layers "*.Cu" "*.Mask")
			(remove_unused_layers no)
			(net "GND")
			(clearance 0.1524)
			(thermal_gap 0.1524)
		)
		(pad "3" thru_hole circle
			(at -2.500122 -2.500122)
			(size 0.762 0.762)
			(drill 0.5588)
			(layers "*.Cu" "*.Mask")
			(remove_unused_layers no)
			(net "GND")
			(clearance 0.1524)
			(thermal_gap 0.1524)
		)
		(pad "4" thru_hole circle
			(at -3.50012 0)
			(size 0.762 0.762)
			(drill 0.5588)
			(layers "*.Cu" "*.Mask")
			(remove_unused_layers no)
			(net "GND")
			(clearance 0.1524)
			(thermal_gap 0.1524)
		)
		(pad "5" thru_hole circle
			(at -2.500122 2.500122)
			(size 0.762 0.762)
			(drill 0.5588)
			(layers "*.Cu" "*.Mask")
			(remove_unused_layers no)
			(net "GND")
			(clearance 0.1524)
			(thermal_gap 0.1524)
		)
		(pad "6" thru_hole circle
			(at 0 3.50012)
			(size 0.762 0.762)
			(drill 0.5588)
			(layers "*.Cu" "*.Mask")
			(remove_unused_layers no)
			(net "GND")
			(clearance 0.1524)
			(thermal_gap 0.1524)
		)
		(pad "7" thru_hole circle
			(at 2.500122 2.500122)
			(size 0.762 0.762)
			(drill 0.5588)
			(layers "*.Cu" "*.Mask")
			(remove_unused_layers no)
			(net "GND")
			(clearance 0.1524)
			(thermal_gap 0.1524)
		)
		(pad "8" thru_hole circle
			(at 3.50012 0)
			(size 0.762 0.762)
			(drill 0.5588)
			(layers "*.Cu" "*.Mask")
			(remove_unused_layers no)
			(net "GND")
			(clearance 0.1524)
			(thermal_gap 0.1524)
		)
		(pad "9" thru_hole circle
			(at 2.500122 -2.500122)
			(size 0.762 0.762)
			(drill 0.5588)
			(layers "*.Cu" "*.Mask")
			(remove_unused_layers no)
			(net "GND")
			(clearance 0.1524)
			(thermal_gap 0.1524)
		)
		(zone
			(layer "F.Cu")
			(hatch none 0.5)
			(connect_pads
				(clearance 0)
			)
			(min_thickness 0.25)
			(keepout
				(tracks not_allowed)
				(vias allowed)
				(pads allowed)
				(copperpour not_allowed)
				(footprints allowed)
			)
			(placement
				(enabled no)
				(sheetname "")
			)
			(fill
				(thermal_gap 0.5)
				(thermal_bridge_width 0.5)
				(island_removal_mode 0)
			)
			(polygon
				(pts
					(arc
						(start 16.599916 -392.80084)
						(mid 8.598916 -384.79984)
						(end 16.599916 -376.79884)
					)
					(arc
						(start 16.599916 -376.79884)
						(mid 18.035016 -378.23394)
						(end 16.599916 -379.66904)
					)
					(arc
						(start 16.599916 -379.66904)
						(mid 11.469116 -384.79984)
						(end 16.599916 -389.93064)
					)
					(arc
						(start 16.599916 -389.93064)
						(mid 18.035016 -391.36574)
						(end 16.599916 -392.80084)
					)
				)
			)
		)
		(zone
			(layer "F.Cu")
			(hatch none 0.5)
			(connect_pads
				(clearance 0)
			)
			(min_thickness 0.25)
			(keepout
				(tracks not_allowed)
				(vias allowed)
				(pads allowed)
				(copperpour not_allowed)
				(footprints allowed)
			)
			(placement
				(enabled no)
				(sheetname "")
			)
			(fill
				(thermal_gap 0.5)
				(thermal_bridge_width 0.5)
				(island_removal_mode 0)
			)
			(polygon
				(pts
					(arc
						(start 16.599916 -392.80084)
						(mid 24.600916 -384.79984)
						(end 16.599916 -376.79884)
					)
					(arc
						(start 16.599916 -376.79884)
						(mid 15.164816 -378.23394)
						(end 16.599916 -379.66904)
					)
					(arc
						(start 16.599916 -379.66904)
						(mid 21.730716 -384.79984)
						(end 16.599916 -389.93064)
					)
					(arc
						(start 16.599916 -389.93064)
						(mid 15.164816 -391.36574)
						(end 16.599916 -392.80084)
					)
				)
			)
		)
		(zone
			(layers "F.Cu" "B.Cu" "In1.Cu" "In2.Cu" "In3.Cu" "In4.Cu" "In5.Cu" "In6.Cu")
			(hatch none 0.5)
			(connect_pads
				(clearance 0)
			)
			(min_thickness 0.25)
			(keepout
				(tracks not_allowed)
				(vias allowed)
				(pads allowed)
				(copperpour not_allowed)
				(footprints allowed)
			)
			(placement
				(enabled no)
				(sheetname "")
			)
			(fill
				(thermal_gap 0.5)
				(thermal_bridge_width 0.5)
				(island_removal_mode 0)
			)
			(polygon
				(pts
					(arc
						(start 16.599916 -382.28778)
						(mid 16.599916 -387.3119)
						(end 16.599916 -382.28778)
					)
				)
			)
		)
	)
	(footprint ""
		(layer "F.Cu")
		(at 66.74104 -206.29118 180)
		(property "Reference" "R120"
			(at -0.150876 -1.42875 0)
			(unlocked yes)
			(layer "F.SilkS")
			(effects
				(font
					(size 0.7874 0.5842)
					(thickness 0.1524)
				)
				(justify left)
			)
		)
		(property "Value" ""
			(at 0 0 180)
			(layer "F.Fab")
			(effects
				(font
					(size 1.27 1.27)
				)
			)
		)
		(duplicate_pad_numbers_are_jumpers no)
		(fp_line
			(start 0.7874 0.4064)
			(end -0.7874 0.4064)
			(stroke
				(width 0.1524)
				(type default)
			)
			(layer "F.SilkS")
		)
		(fp_line
			(start 0.7874 -0.4064)
			(end 0.7874 0.4064)
			(stroke
				(width 0.1524)
				(type default)
			)
			(layer "F.SilkS")
		)
		(fp_line
			(start -0.7874 0.4064)
			(end -0.7874 -0.4064)
			(stroke
				(width 0.1524)
				(type default)
			)
			(layer "F.SilkS")
		)
		(fp_line
			(start -0.7874 -0.4064)
			(end 0.7874 -0.4064)
			(stroke
				(width 0.1524)
				(type default)
			)
			(layer "F.SilkS")
		)
		(fp_poly
			(pts
				(xy -0.508 0.2794) (xy -0.508 0.2286) (xy -0.635 0.2286) (xy -0.635 -0.254) (xy -0.5334 -0.254)
				(xy -0.5334 -0.2794) (xy 0.5334 -0.2794) (xy 0.5334 -0.254) (xy 0.635 -0.254) (xy 0.635 0.254) (xy 0.5334 0.254)
				(xy 0.5334 0.2794)
			)
			(stroke
				(width 0)
				(type default)
			)
			(fill no)
			(layer "F.CrtYd")
		)
		(pad "1" smd rect
			(at 0.40005 0 180)
			(size 0.4572 0.508)
			(layers "F.Cu" "F.Mask" "F.Paste")
			(net "PSU3_REMOTE_R2_N")
		)
		(pad "2" smd rect
			(at -0.40005 0 180)
			(size 0.4572 0.508)
			(layers "F.Cu" "F.Mask" "F.Paste")
			(net "GND")
		)
	)
	(footprint ""
		(layer "F.Cu")
		(at 71.903844 -42.631106 90)
		(property "Reference" "C14"
			(at -1.201928 4.801108 90)
			(unlocked yes)
			(layer "F.SilkS")
			(effects
				(font
					(size 0.7874 0.5842)
					(thickness 0.1524)
				)
				(justify left)
			)
		)
		(property "Value" ""
			(at 0 0 90)
			(layer "F.Fab")
			(effects
				(font
					(size 1.27 1.27)
				)
			)
		)
		(duplicate_pad_numbers_are_jumpers no)
		(fp_line
			(start 0.7874 -0.4064)
			(end 0.7874 0.4064)
			(stroke
				(width 0.1524)
				(type default)
			)
			(layer "F.SilkS")
		)
		(fp_line
			(start -0.7874 -0.4064)
			(end 0.7874 -0.4064)
			(stroke
				(width 0.1524)
				(type default)
			)
			(layer "F.SilkS")
		)
		(fp_line
			(start 0 0.381)
			(end 0 -0.381)
			(stroke
				(width 0.1524)
				(type default)
			)
			(layer "F.SilkS")
		)
		(fp_line
			(start 0.7874 0.4064)
			(end -0.7874 0.4064)
			(stroke
				(width 0.1524)
				(type default)
			)
			(layer "F.SilkS")
		)
		(fp_line
			(start -0.7874 0.4064)
			(end -0.7874 -0.4064)
			(stroke
				(width 0.1524)
				(type default)
			)
			(layer "F.SilkS")
		)
		(fp_poly
			(pts
				(xy -0.5334 0.254) (xy -0.635 0.254) (xy -0.635 0.2286) (xy -0.635 -0.254) (xy -0.5334 -0.254) (xy -0.5334 -0.2794)
				(xy 0.5334 -0.2794) (xy 0.5334 -0.254) (xy 0.635 -0.254) (xy 0.635 0.254) (xy 0.5334 0.254) (xy 0.5334 0.2794)
				(xy -0.508 0.2794) (xy -0.5334 0.2794)
			)
			(stroke
				(width 0)
				(type default)
			)
			(fill no)
			(layer "F.CrtYd")
		)
		(pad "1" smd rect
			(at 0.40005 0 90)
			(size 0.4572 0.508)
			(layers "F.Cu" "F.Mask" "F.Paste")
			(net "P12V")
		)
		(pad "2" smd rect
			(at -0.40005 0 90)
			(size 0.4572 0.508)
			(layers "F.Cu" "F.Mask" "F.Paste")
			(net "GND")
		)
	)
	(footprint ""
		(layer "F.Cu")
		(at 74.0537 -459.732634 -90)
		(property "Reference" "C73"
			(at -2.962656 -0.345948 90)
			(unlocked yes)
			(layer "F.SilkS")
			(effects
				(font
					(size 0.7874 0.5842)
					(thickness 0.1524)
				)
				(justify left)
			)
		)
		(property "Value" ""
			(at 0 0 270)
			(layer "F.Fab")
			(effects
				(font
					(size 1.27 1.27)
				)
			)
		)
		(duplicate_pad_numbers_are_jumpers no)
		(fp_line
			(start -0.7874 0.4064)
			(end -0.7874 -0.4064)
			(stroke
				(width 0.1524)
				(type default)
			)
			(layer "F.SilkS")
		)
		(fp_line
			(start 0.7874 0.4064)
			(end -0.7874 0.4064)
			(stroke
				(width 0.1524)
				(type default)
			)
			(layer "F.SilkS")
		)
		(fp_line
			(start 0 0.381)
			(end 0 -0.381)
			(stroke
				(width 0.1524)
				(type default)
			)
			(layer "F.SilkS")
		)
		(fp_line
			(start -0.7874 -0.4064)
			(end 0.7874 -0.4064)
			(stroke
				(width 0.1524)
				(type default)
			)
			(layer "F.SilkS")
		)
		(fp_line
			(start 0.7874 -0.4064)
			(end 0.7874 0.4064)
			(stroke
				(width 0.1524)
				(type default)
			)
			(layer "F.SilkS")
		)
		(fp_poly
			(pts
				(xy -0.5334 0.254) (xy -0.635 0.254) (xy -0.635 0.2286) (xy -0.635 -0.254) (xy -0.5334 -0.254) (xy -0.5334 -0.2794)
				(xy 0.5334 -0.2794) (xy 0.5334 -0.254) (xy 0.635 -0.254) (xy 0.635 0.254) (xy 0.5334 0.254) (xy 0.5334 0.2794)
				(xy -0.508 0.2794) (xy -0.5334 0.2794)
			)
			(stroke
				(width 0)
				(type default)
			)
			(fill no)
			(layer "F.CrtYd")
		)
		(pad "1" smd rect
			(at 0.40005 0 270)
			(size 0.4572 0.508)
			(layers "F.Cu" "F.Mask" "F.Paste")
			(net "P12V")
		)
		(pad "2" smd rect
			(at -0.40005 0 270)
			(size 0.4572 0.508)
			(layers "F.Cu" "F.Mask" "F.Paste")
			(net "GND")
		)
	)
	(footprint ""
		(layer "F.Cu")
		(at 66.7004 -209.195416 180)
		(property "Reference" "R119"
			(at 0.958596 0.97282 0)
			(unlocked yes)
			(layer "F.SilkS")
			(effects
				(font
					(size 0.7874 0.5842)
					(thickness 0.1524)
				)
				(justify left)
			)
		)
		(property "Value" ""
			(at 0 0 180)
			(layer "F.Fab")
			(effects
				(font
					(size 1.27 1.27)
				)
			)
		)
		(duplicate_pad_numbers_are_jumpers no)
		(fp_line
			(start 0.7874 0.4064)
			(end -0.7874 0.4064)
			(stroke
				(width 0.1524)
				(type default)
			)
			(layer "F.SilkS")
		)
		(fp_line
			(start 0.7874 -0.4064)
			(end 0.7874 0.4064)
			(stroke
				(width 0.1524)
				(type default)
			)
			(layer "F.SilkS")
		)
		(fp_line
			(start -0.7874 0.4064)
			(end -0.7874 -0.4064)
			(stroke
				(width 0.1524)
				(type default)
			)
			(layer "F.SilkS")
		)
		(fp_line
			(start -0.7874 -0.4064)
			(end 0.7874 -0.4064)
			(stroke
				(width 0.1524)
				(type default)
			)
			(layer "F.SilkS")
		)
		(fp_poly
			(pts
				(xy -0.508 0.2794) (xy -0.508 0.2286) (xy -0.635 0.2286) (xy -0.635 -0.254) (xy -0.5334 -0.254)
				(xy -0.5334 -0.2794) (xy 0.5334 -0.2794) (xy 0.5334 -0.254) (xy 0.635 -0.254) (xy 0.635 0.254) (xy 0.5334 0.254)
				(xy 0.5334 0.2794)
			)
			(stroke
				(width 0)
				(type default)
			)
			(fill no)
			(layer "F.CrtYd")
		)
		(pad "1" smd rect
			(at 0.40005 0 180)
			(size 0.4572 0.508)
			(layers "F.Cu" "F.Mask" "F.Paste")
			(net "PSU3_REMOTE_R2_P")
		)
		(pad "2" smd rect
			(at -0.40005 0 180)
			(size 0.4572 0.508)
			(layers "F.Cu" "F.Mask" "F.Paste")
			(net "P12V")
		)
	)
	(footprint ""
		(layer "F.Cu")
		(at 27.639264 -285.429452 -90)
		(property "Reference" "R109"
			(at -1.498854 1.234948 90)
			(unlocked yes)
			(layer "F.SilkS")
			(effects
				(font
					(size 0.7874 0.5842)
					(thickness 0.1524)
				)
				(justify left)
			)
		)
		(property "Value" ""
			(at 0 0 270)
			(layer "F.Fab")
			(effects
				(font
					(size 1.27 1.27)
				)
			)
		)
		(duplicate_pad_numbers_are_jumpers no)
		(fp_line
			(start -0.7874 0.4064)
			(end -0.7874 -0.4064)
			(stroke
				(width 0.1524)
				(type default)
			)
			(layer "F.SilkS")
		)
		(fp_line
			(start 0.7874 0.4064)
			(end -0.7874 0.4064)
			(stroke
				(width 0.1524)
				(type default)
			)
			(layer "F.SilkS")
		)
		(fp_line
			(start -0.7874 -0.4064)
			(end 0.7874 -0.4064)
			(stroke
				(width 0.1524)
				(type default)
			)
			(layer "F.SilkS")
		)
		(fp_line
			(start 0.7874 -0.4064)
			(end 0.7874 0.4064)
			(stroke
				(width 0.1524)
				(type default)
			)
			(layer "F.SilkS")
		)
		(fp_poly
			(pts
				(xy -0.508 0.2794) (xy -0.508 0.2286) (xy -0.635 0.2286) (xy -0.635 -0.254) (xy -0.5334 -0.254)
				(xy -0.5334 -0.2794) (xy 0.5334 -0.2794) (xy 0.5334 -0.254) (xy 0.635 -0.254) (xy 0.635 0.254) (xy 0.5334 0.254)
				(xy 0.5334 0.2794)
			)
			(stroke
				(width 0)
				(type default)
			)
			(fill no)
			(layer "F.CrtYd")
		)
		(pad "1" smd rect
			(at 0.40005 0 270)
			(size 0.4572 0.508)
			(layers "F.Cu" "F.Mask" "F.Paste")
			(net "PSU4_REMOTE_N")
		)
		(pad "2" smd rect
			(at -0.40005 0 270)
			(size 0.4572 0.508)
			(layers "F.Cu" "F.Mask" "F.Paste")
			(net "PSU4_REMOTE_R_N")
		)
	)
	(footprint ""
		(layer "F.Cu")
		(at 79.524606 -14.939772 -90)
		(property "Reference" "C5"
			(at -1.75133 0.0254 90)
			(unlocked yes)
			(layer "F.SilkS")
			(effects
				(font
					(size 0.7874 0.5842)
					(thickness 0.1524)
				)
				(justify left)
			)
		)
		(property "Value" ""
			(at 0 0 270)
			(layer "F.Fab")
			(effects
				(font
					(size 1.27 1.27)
				)
			)
		)
		(duplicate_pad_numbers_are_jumpers no)
		(fp_line
			(start -0.7874 0.4064)
			(end -0.7874 -0.4064)
			(stroke
				(width 0.1524)
				(type default)
			)
			(layer "F.SilkS")
		)
		(fp_line
			(start 0.7874 0.4064)
			(end -0.7874 0.4064)
			(stroke
				(width 0.1524)
				(type default)
			)
			(layer "F.SilkS")
		)
		(fp_line
			(start 0 0.381)
			(end 0 -0.381)
			(stroke
				(width 0.1524)
				(type default)
			)
			(layer "F.SilkS")
		)
		(fp_line
			(start -0.7874 -0.4064)
			(end 0.7874 -0.4064)
			(stroke
				(width 0.1524)
				(type default)
			)
			(layer "F.SilkS")
		)
		(fp_line
			(start 0.7874 -0.4064)
			(end 0.7874 0.4064)
			(stroke
				(width 0.1524)
				(type default)
			)
			(layer "F.SilkS")
		)
		(fp_poly
			(pts
				(xy -0.5334 0.254) (xy -0.635 0.254) (xy -0.635 0.2286) (xy -0.635 -0.254) (xy -0.5334 -0.254) (xy -0.5334 -0.2794)
				(xy 0.5334 -0.2794) (xy 0.5334 -0.254) (xy 0.635 -0.254) (xy 0.635 0.254) (xy 0.5334 0.254) (xy 0.5334 0.2794)
				(xy -0.508 0.2794) (xy -0.5334 0.2794)
			)
			(stroke
				(width 0)
				(type default)
			)
			(fill no)
			(layer "F.CrtYd")
		)
		(pad "1" smd rect
			(at 0.40005 0 270)
			(size 0.4572 0.508)
			(layers "F.Cu" "F.Mask" "F.Paste")
			(net "P12V")
		)
		(pad "2" smd rect
			(at -0.40005 0 270)
			(size 0.4572 0.508)
			(layers "F.Cu" "F.Mask" "F.Paste")
			(net "GND")
		)
	)
	(footprint ""
		(layer "F.Cu")
		(at 91.399868 -20.01012)
		(property "Reference" "H25"
			(at -5.1308 -5.23113 0)
			(unlocked yes)
			(layer "F.SilkS")
			(effects
				(font
					(size 0.7874 0.5842)
					(thickness 0.1524)
				)
				(justify left)
			)
		)
		(property "Value" ""
			(at 0 0 0)
			(layer "F.Fab")
			(effects
				(font
					(size 1.27 1.27)
				)
			)
		)
		(duplicate_pad_numbers_are_jumpers no)
		(fp_circle
			(center 0 0)
			(end 4.826 0)
			(stroke
				(width 0.1524)
				(type default)
			)
			(fill no)
			(layer "F.SilkS")
		)
		(fp_circle
			(center 0 0)
			(end 4.826 0)
			(stroke
				(width 0.1524)
				(type default)
			)
			(fill no)
			(layer "B.SilkS")
		)
		(fp_poly
			(pts
				(arc
					(start 0 4.0132)
					(mid 0 -4.0132)
					(end 0 4.0132)
				)
			)
			(stroke
				(width 0)
				(type default)
			)
			(fill no)
			(layer "F.CrtYd")
		)
		(pad "" np_thru_hole circle
			(at 0 0)
			(size 8.001 8.001)
			(drill 8.001)
			(layers "*.Cu" "*.Mask")
			(clearance 0.381)
			(thermal_gap 0.381)
		)
		(zone
			(layers "F.Cu" "B.Cu" "In1.Cu" "In2.Cu" "In3.Cu" "In4.Cu" "In5.Cu" "In6.Cu")
			(hatch none 0.5)
			(connect_pads
				(clearance 0)
			)
			(min_thickness 0.25)
			(keepout
				(tracks not_allowed)
				(vias allowed)
				(pads allowed)
				(copperpour not_allowed)
				(footprints allowed)
			)
			(placement
				(enabled no)
				(sheetname "")
			)
			(fill
				(thermal_gap 0.5)
				(thermal_bridge_width 0.5)
				(island_removal_mode 0)
			)
			(polygon
				(pts
					(arc
						(start 91.399868 -15.48892)
						(mid 91.399868 -24.53132)
						(end 91.399868 -15.48892)
					)
				)
			)
		)
	)
)
